# S9S_MB_2U (Grand Teton) — schematic parts with pin connectivity, parts 5880–5880 of 6093; source: Cadence DE-HDL packaged netlist (pstxprt.dat, pstxnet.dat, pstchip.dat)

U2  SOCKET4677_AZIF0045P001C01CS  SOCKET4677_AZIF0045-P001C01CS IO  pkg SOCKET4677_82X64-5XA_H466  page 13  (pins 1957-2282 of 4677)
  CH69  RSVD99  BI  = NC_CPU0_MDFI_DIE11_EW1
  CH71  RSVD100  BI  = TP_PWRGD_S0_PWROK_CPU0_LVC1
  CH73  VSS728  POWER  = GND
  CH75  UPI3_TX_DP20  OUT  = NC
  CH77  UPI3_TX_DN17  OUT  = NC
  CH79  VSS729  POWER  = GND
  CH81  VCCIN318  POWER  = PVCCIN_CPU0
  CH83  VSS731  POWER  = GND
  CH85  VSS732  POWER  = GND
  CH87  VSS733  POWER  = GND
  CH89  VSS734  POWER  = GND
  CH91  VCCIN319  POWER  = PVCCIN_CPU0
  CJ1  UPI1_RX_DN19  IN  = UPI_CPU1_CPU0_P0P1_DP<19>
  CJ3  VCCINFAON2  POWER  = PVCCINFAON_CPU0
  CJ5  UPI1_TX_DN18  OUT  = UPI_CPU0_CPU1_P1P0_DP<18>
  CJ7  VCCINFAON3  POWER  = PVCCINFAON_CPU0
  CJ9  PE1_RX_DP2  IN  = P5E_CPU0_PE1_RX_DP<2>
  CJ11  VCCINFAON45  POWER  = PVCCINFAON_CPU0
  CJ13  PE1_TX_DN3  OUT  = P5E_CPU0_PE1_TX_DN<3>
  CJ15  VCCINFAON1  POWER  = PVCCINFAON_CPU0
  CJ17  DMI_TX_DN5  OUT  = DMI_CPU0_PCH_TX_DN<5>
  CJ19  VCCINFAON46  POWER  = PVCCINFAON_CPU0
  CJ21  RSVD101  BI  = TP_IBL_GRST_WARN_PLD_R_N
  CJ23  RSVD102  BI  = TP_I2C_S3M_RTC_CPU0_SDA
  CJ25  RSVD103  BI  = TP_I2C_S3M_RTC_CPU0_ALERT_N
  CJ60  VSS736  POWER  = GND
  CJ62  RSVD104  BI  = NC_CPU0_VIEWPIN_DIE11<0>
  CJ64  TEST_1  BI  = PU_S3M_CPU0_CPLD_CONFD
  CJ66  RSVD105  BI  = TP_SGPIO_S3M_CPU0_GSXDLOAD_R
  CJ68  RSVD106  BI  = NC_CPU0_MDFI_DIE11_NS0
  CJ70  RSVD107  BI  = NC_CPU0_MDFI_DIE11_EW0
  CJ72  RSVD108  BI  = PUD_XTAL_CPU0_MODE1
  CJ74  UPI3_TX_DN21  OUT  = NC
  CJ76  VSS383  POWER  = GND
  CJ78  UPI3_TX_DP17  OUT  = NC
  CJ80  VSS737  POWER  = GND
  CJ82  VCCIN320  POWER  = PVCCIN_CPU0
  CJ84  VCCIN321  POWER  = PVCCIN_CPU0
  CJ86  VCCIN322  POWER  = PVCCIN_CPU0
  CJ88  VCCIN323  POWER  = PVCCIN_CPU0
  CJ90  VCCIN324  POWER  = PVCCIN_CPU0
  CK2  UPI1_RX_DP19  IN  = UPI_CPU1_CPU0_P0P1_DN<19>
  CK4  VSS396  POWER  = GND
  CK6  UPI1_TX_DP18  OUT  = UPI_CPU0_CPU1_P1P0_DN<18>
  CK8  VSS746  POWER  = GND
  CK10  PE1_RX_DN2  IN  = P5E_CPU0_PE1_RX_DN<2>
  CK12  VSS740  POWER  = GND
  CK14  PE1_TX_DN2  OUT  = P5E_CPU0_PE1_TX_DN<2>
  CK16  VSS741  POWER  = GND
  CK18  DMI_TX_DN6  OUT  = DMI_CPU0_PCH_TX_DN<6>
  CK20  VSS742  POWER  = GND
  CK22  RSVD109  BI  = TP_FM_IBL_SYS_RST_CPU0_N
  CK24  RSVD110  BI  = TP_CPU0_PWRBTN_N
  CK26  VSS743  POWER  = GND
  CK61  RSVD111  BI  = TP_CPU0_SPARE8
  CK63  VSS744  POWER  = GND
  CK65  TEST_2  BI  = FM_S3M_CPU0_CPLD_CONFIG_N
  CK67  RSVD112  BI  = NC_CPU0_MDFI_DIE11_NS1
  CK69  VSS745  POWER  = GND
  CK71  UPI3_AC_COUPLING  IN  = PU_CPU0_UPI3_AC_COUPLING
  CK73  VCCFA_EHV_FIVRA35  POWER  = PVCCFA_EHV_FIVRA_CPU0
  CK75  UPI3_TX_DP21  OUT  = NC
  CK77  UPI3_TX_DN16  OUT  = NC
  CK79  VCCFA_EHV_FIVRA36  POWER  = PVCCFA_EHV_FIVRA_CPU0
  CK81  VSS749  POWER  = GND
  CK83  VCCIN325  POWER  = PVCCIN_CPU0
  CK85  VCCIN326  POWER  = PVCCIN_CPU0
  CK87  VCCIN327  POWER  = PVCCIN_CPU0
  CK89  VCCIN328  POWER  = PVCCIN_CPU0
  CK91  VCCIN329  POWER  = PVCCIN_CPU0
  CL1  VSS750  POWER  = GND
  CL3  UPI1_RX_DN18  IN  = UPI_CPU1_CPU0_P0P1_DN<18>
  CL5  VSS754  POWER  = GND
  CL7  UPI1_TX_DP17  OUT  = UPI_CPU0_CPU1_P1P0_DN<17>
  CL9  VSS760  POWER  = GND
  CL11  PE1_RX_DN1  IN  = P5E_CPU0_PE1_RX_DN<1>
  CL13  VSS751  POWER  = GND
  CL15  PE1_TX_DP2  OUT  = P5E_CPU0_PE1_TX_DP<2>
  CL17  VSS752  POWER  = GND
  CL19  DMI_TX_DP6  OUT  = DMI_CPU0_PCH_TX_DP<6>
  CL21  RSVD113  BI  = TP_IBL_PLT_RST_SYNC_N
  CL23  RSVD114  BI  = TP_I2C_S3M_RTC_CPU0_SCL
  CL25  PMSYNC1  BI  = TP_H_SBLINK2_CPU0_PMSYNC
  CL60  RSVD115  BI  = TP_CPU0_SPARE7
  CL62  VSS755  POWER  = GND
  CL64  RSVD116  BI  = NC_CPU0_VIEWPIN_DIE11<3>
  CL66  RSVD117  BI  = TP_CPU0_SSC_SYNC
  CL68  RSVD118  BI  = NC_CPU0_PE3_APROBE<0>
  CL70  RSVD119  BI  = TP_CPU0_SPARE12
  CL72  RSVD120  BI  = PUD_XTAL_CPU0_MODE0
  CL74  VSS756  POWER  = GND
  CL76  UPI3_TX_DP18  OUT  = NC
  CL78  VSS757  POWER  = GND
  CL80  VSS758  POWER  = GND
  CL82  VSS759  POWER  = GND
  CL84  VCCIN330  POWER  = PVCCIN_CPU0
  CL86  VCCIN331  POWER  = PVCCIN_CPU0
  CL88  VCCIN332  POWER  = PVCCIN_CPU0
  CL90  VCCIN333  POWER  = PVCCIN_CPU0
  CM2  UPI1_RX_DP18  IN  = UPI_CPU1_CPU0_P0P1_DP<18>
  CM4  VSS764  POWER  = GND
  CM6  UPI1_TX_DN17  OUT  = UPI_CPU0_CPU1_P1P0_DP<17>
  CM8  VSS769  POWER  = GND
  CM10  PE1_RX_DP1  IN  = P5E_CPU0_PE1_RX_DP<1>
  CM12  VSS761  POWER  = GND
  CM14  PE1_TX_DP1  OUT  = P5E_CPU0_PE1_TX_DP<1>
  CM16  VSS436  POWER  = GND
  CM18  DMI_TX_DP7  OUT  = DMI_CPU0_PCH_TX_DN<7>
  CM20  VSS762  POWER  = GND
  CM22  VSS438  POWER  = GND
  CM24  VSS763  POWER  = GND
  CM26  PMDOWN2  BI  = TP_H_SBLINK3_CPU0_PMDOWN
  CM61  VSS765  POWER  = GND
  CM63  RSVD121  BI  = NC_CPU0_VIEWPIN_DIE11<2>
  CM65  VSS766  POWER  = GND
  CM67  VSS767  POWER  = GND
  CM69  RSVD122  BI  = NC_CPU0_PE3_APROBE<1>
  CM71  PIROM_SDA  BI  = SMB_S3M_CPU0_PIROM_3V3AUX_SDA_1
  CM73  VCCFA_EHV_FIVRA37  POWER  = PVCCFA_EHV_FIVRA_CPU0
  CM75  UPI3_TX_DN18  OUT  = NC
  CM77  UPI3_TX_DP16  OUT  = NC
  CM79  VSS768  POWER  = GND
  CM81  VSS770  POWER  = GND
  CM83  VSS771  POWER  = GND
  CM85  VSS772  POWER  = GND
  CM87  VCCIN334  POWER  = PVCCIN_CPU0
  CM89  VCCIN339  POWER  = PVCCIN_CPU0
  CM91  VCCIN335  POWER  = PVCCIN_CPU0
  CN1  UPI1_RX_DN17  IN  = UPI_CPU1_CPU0_P0P1_DP<17>
  CN3  VCCINFAON6  POWER  = PVCCINFAON_CPU0
  CN5  UPI1_TX_DN16  OUT  = UPI_CPU0_CPU1_P1P0_DP<16>
  CN7  VCCINFAON9  POWER  = PVCCINFAON_CPU0
  CN9  PE1_RX_DP0  IN  = P5E_CPU0_PE1_RX_DP<0>
  CN11  VCCINFAON4  POWER  = PVCCINFAON_CPU0
  CN13  PE1_TX_DN1  OUT  = P5E_CPU0_PE1_TX_DN<1>
  CN15  VCCINFAON5  POWER  = PVCCINFAON_CPU0
  CN17  DMI_TX_DN7  OUT  = DMI_CPU0_PCH_TX_DP<7>
  CN19  VCCINFAON47  POWER  = PVCCINFAON_CPU0
  CN21  RSVD123  BI  = TP_IBL_SLPS4_CPU0_R_N
  CN23  RSVD124  BI  = TP_FM_IBL_ADR_ACK_CPU0
  CN25  PMSYNC0  BI  = H_CPU0_PMSYNC_CPU1_R
  CN60  RSVD125  BI  = NC_CPU0_LGSSPARE1
  CN62  RSVD126  BI  = NC_CPU0_VIEWPIN_DIE11<1>
  CN64  VCCINFAON7  POWER  = PVCCINFAON_CPU0
  CN66  VCCINFAON8  POWER  = PVCCINFAON_CPU0
  CN68  VSS773  POWER  = GND
  CN70  VSS774  POWER  = GND
  CN72  VSS775  POWER  = GND
  CN74  VSS777  POWER  = GND
  CN76  VSS471  POWER  = GND
  CN78  VCCFA_EHV_FIVRA38  POWER  = PVCCFA_EHV_FIVRA_CPU0
  CN80  UPI3_RX_DN21  IN  = GND
  CN82  UPI3_RX_DP20  IN  = GND
  CN84  VSS778  POWER  = GND
  CN86  VSS779  POWER  = GND
  CN88  VCCIN336  POWER  = PVCCIN_CPU0
  CN90  VCCIN337  POWER  = PVCCIN_CPU0
  CP2  UPI1_RX_DP17  IN  = UPI_CPU1_CPU0_P0P1_DN<17>
  CP4  VSS782  POWER  = GND
  CP6  UPI1_TX_DP16  OUT  = UPI_CPU0_CPU1_P1P0_DN<16>
  CP8  VSS785  POWER  = GND
  CP10  PE1_RX_DN0  IN  = P5E_CPU0_PE1_RX_DN<0>
  CP12  VSS780  POWER  = GND
  CP14  PE1_TX_DN0  OUT  = P5E_CPU0_PE1_TX_DN<0>
  CP16  VSS478  POWER  = GND
  CP18  VSS781  POWER  = GND
  CP20  PMFAST_WAKE_N  BI  = H_CPU0_PM_FAST_WAKE_N
  CP22  RSVD127  BI  = TP_JTAG_CPU0_PLD_TDO
  CP24  RSVD128  BI  = TP_FM_IBL_ADR_COMPLETE_CPU0_R
  CP26  PMDOWN1  BI  = TP_H_SBLINK2_CPU0_PMDOWN
  CP61  RSVD129  BI  = NC_CPU0_LGSSPARE5
  CP63  VCCINFAON48  POWER  = PVCCINFAON_CPU0
  CP65  VCCINFAON10  POWER  = PVCCINFAON_CPU0
  CP67  VCCINFAON11  POWER  = PVCCINFAON_CPU0
  CP69  RSVD130  BI  = NC_CPU0_UPI3_APROBE<0>
  CP71  PIROM_AD2  IN  = PD_PIROM_CPU0_ADDR2
  CP73  VCCFA_EHV_FIVRA39  POWER  = PVCCFA_EHV_FIVRA_CPU0
  CP75  VSS783  POWER  = GND
  CP77  VSS784  POWER  = GND
  CP79  VSS493  POWER  = GND
  CP81  UPI3_RX_DN20  IN  = GND
  CP83  VSS786  POWER  = GND
  CP85  PE3_TX_DN15  OUT  = P5E_CPU0_PE3_TX_DN<15>
  CP87  VSS787  POWER  = GND
  CP89  VCCIN338  POWER  = PVCCIN_CPU0
  CP91  VSS788  POWER  = GND
  CR1  VSS789  POWER  = GND
  CR3  UPI1_RX_DN16  IN  = UPI_CPU1_CPU0_P0P1_DN<16>
  CR5  VSS794  POWER  = GND
  CR7  UPI1_TX_DP15  OUT  = UPI_CPU0_CPU1_P1P0_DN<15>
  CR9  VSS801  POWER  = GND
  CR11  VSS790  POWER  = GND
  CR13  VSS792  POWER  = GND
  CR15  PE1_TX_DP0  OUT  = P5E_CPU0_PE1_TX_DP<0>
  CR17  VSS793  POWER  = GND
  CR19  PMSYNC4  BI  = TP_H_SBLINK5_CPU0_PMSYNC
  CR21  RSVD131  BI  = TP_IBL_SLPS3_CPU0_R_N
  CR23  RSVD132  BI  = NC_CPU0_VIEWPIN_DIE10<0>
  CR25  RSVD133  BI  = NC_CPU0_VIEWPIN_GNR2
  CR60  RSVD134  BI  = NC_CPU0_LGSSPARE0
  CR62  VSS795  POWER  = GND
  CR64  VSS796  POWER  = GND
  CR66  VCCINFAON54  POWER  = PVCCINFAON_CPU0
  CR68  RSVD135  BI  = NC_CPU0_UPI3_APROBE<1>
  CR70  PIROM_AD0  IN  = PD_PIROM_CPU0_ADDR0
  CR72  PIROM_SM_WP  IN  = PU_PIROM_CPU0_SM_WP
  CR74  UPI3_TX_DN15  OUT  = NC
  CR76  UPI3_TX_DP14  OUT  = NC
  CR78  VSS514  POWER  = GND
  CR80  UPI3_RX_DP21  IN  = GND
  CR82  UPI3_RX_DN18  IN  = GND
  CR84  VSS797  POWER  = GND
  CR86  PE3_TX_DP15  OUT  = P5E_CPU0_PE3_TX_DP<15>
  CR88  VSS800  POWER  = GND
  CR90  VSS803  POWER  = GND
  CT2  UPI1_RX_DP16  IN  = UPI_CPU1_CPU0_P0P1_DP<16>
  CT4  VSS526  POWER  = GND
  CT6  UPI1_TX_DN15  OUT  = UPI_CPU0_CPU1_P1P0_DP<15>
  CT8  VSS534  POWER  = GND
  CT10  VSS804  POWER  = GND
  CT12  VSS805  POWER  = GND
  CT14  PE2_TX_DP0  OUT  = P5E_CPU0_PE2_TX_DP<0>
  CT16  VSS521  POWER  = GND
  CT18  DDR4567_SPDSDA  BI  = I3C_SPD_DDREFGH_CPU0_SDA
  CT20  TXT_PLTEN  IN  = PD_CPU0_TXT_PLTEN
  CT22  RSVD136  BI  = TP_JTAG_CPU0_PLD_TDI
  CT24  RSVD137  BI  = TP_FM_IBL_ADR_TRIGGER_CPU0_R
  CT26  RSVD138  BI  = NC_CPU0_VIEWPIN_GNR0
  CT61  SOCKET_ID2  IN  = PU_CPU0_SOCKET_ID2
  CT63  VCCINFAON49  POWER  = PVCCINFAON_CPU0
  CT65  VCCINFAON12  POWER  = PVCCINFAON_CPU0
  CT67  VCCINFAON13  POWER  = PVCCINFAON_CPU0
  CT69  VSS810  POWER  = GND
  CT71  PIROM_AD1  IN  = PD_PIROM_CPU0_ADDR1
  CT73  VSS811  POWER  = GND
  CT75  UPI3_TX_DN14  OUT  = NC
  CT77  VCCFA_EHV_FIVRA40  POWER  = PVCCFA_EHV_FIVRA_CPU0
  CT79  UPI3_RX_DN22  IN  = GND
  CT81  VSS812  POWER  = GND
  CT83  UPI3_RX_DP18  IN  = GND
  CT85  VCCFA_EHV_FIVRA41  POWER  = PVCCFA_EHV_FIVRA_CPU0
  CT87  PE3_TX_DN14  OUT  = P5E_CPU0_PE3_TX_DN<14>
  CT89  VSS537  POWER  = GND
  CT91  PE3_RX_DP15  IN  = P5E_CPU0_PE3_RX_DP<15>
  CU1  UPI1_RX_DP15  IN  = UPI_CPU1_CPU0_P0P1_DP<15>
  CU3  VCCINFAON16  POWER  = PVCCINFAON_CPU0
  CU5  UPI1_TX_DN14  OUT  = UPI_CPU0_CPU1_P1P0_DP<14>
  CU7  VCCINFAON18  POWER  = PVCCINFAON_CPU0
  CU9  PE2_RX_DN0  IN  = P5E_CPU0_PE2_RX_DN<0>
  CU11  VCCINFAON14  POWER  = PVCCINFAON_CPU0
  CU13  PE2_TX_DN0  OUT  = P5E_CPU0_PE2_TX_DN<0>
  CU15  VCCINFAON15  POWER  = PVCCINFAON_CPU0
  CU17  DDR4567_SPDSCL  OUT  = I3C_SPD_DDREFGH_CPU0_SCL
  CU19  VSS813  POWER  = GND
  CU21  VSS814  POWER  = GND
  CU23  VSS815  POWER  = GND
  CU25  VSS544  POWER  = GND
  CU60  VSS816  POWER  = GND
  CU62  RSVD139  BI  = NC_CPU0_LGSSPARE2
  CU64  VCCINFAON17  POWER  = PVCCINFAON_CPU0
  CU66  VSS818  POWER  = GND
  CU68  VSS819  POWER  = GND
  CU70  PIROM_SCL  IN  = SMB_S3M_CPU0_PIROM_3V3AUX_SCL_1
  CU72  VSS553  POWER  = GND
  CU74  UPI3_TX_DP15  OUT  = NC
  CU76  UPI3_TX_DN13  OUT  = NC
  CU78  VSS554  POWER  = GND
  CU80  UPI3_RX_DP22  IN  = GND
  CU82  UPI3_RX_DN17  IN  = GND
  CU84  VSS822  POWER  = GND
  CU86  PE3_TX_DP14  OUT  = P5E_CPU0_PE3_TX_DP<14>
  CU88  VSS823  POWER  = GND
  CU90  PE3_RX_DN15  IN  = P5E_CPU0_PE3_RX_DN<15>
  CV2  UPI1_RX_DN15  IN  = UPI_CPU1_CPU0_P0P1_DN<15>
  CV4  VSS825  POWER  = GND
  CV6  UPI1_TX_DP14  OUT  = UPI_CPU0_CPU1_P1P0_DN<14>
  CV8  VSS827  POWER  = GND
  CV10  PE2_RX_DP0  IN  = P5E_CPU0_PE2_RX_DP<0>
  CV12  VSS824  POWER  = GND
  CV14  PE2_TX_DN1  OUT  = P5E_CPU0_PE2_TX_DN<1>
  CV16  VSS558  POWER  = GND
  CV18  PMDOWN4  BI  = TP_H_SBLINK5_CPU0_PMDOWN
  CV20  PLT_AUX_PWRGOOD  IN  = PWRGD_PLT_AUX_CPU0_LVT3
  CV22  RSVD140  BI  = TP_JTAG_CPU0_PLD_TMS
  CV24  RSVD141  BI  = NC_CPU0_VIEWPIN_DIE10<2>
  CV26  VSS562  POWER  = GND
  CV61  VCCINFAON50  POWER  = PVCCINFAON_CPU0
  CV63  VCCINFAON51  POWER  = PVCCINFAON_CPU0
  CV65  VCCINFAON19  POWER  = PVCCINFAON_CPU0
  CV67  VCCINFAON20  POWER  = PVCCINFAON_CPU0
  CV69  RSVD142  BI  = NC_UART_IBL_CPU0_TXD
  CV71  RSVD143  BI  = NC_UART_IBL_CPU0_CTS
  CV73  UPI3_TX_DN22  OUT  = NC
  CV75  VSS826  POWER  = GND
  CV77  UPI3_TX_DP13  OUT  = NC
  CV79  VSS571  POWER  = GND
  CV81  UPI3_RX_DP19  IN  = GND
  CV83  VSS828  POWER  = GND
  CV85  PE3_TX_DN13  OUT  = P5E_CPU0_PE3_TX_DN<13>
  CV87  VSS831  POWER  = GND
  CV89  PE3_RX_DN14  IN  = P5E_CPU0_PE3_RX_DN<14>
  CV91  VSS833  POWER  = GND
  CW1  VSS834  POWER  = GND
  CW3  UPI1_RX_DP14  IN  = UPI_CPU1_CPU0_P0P1_DP<14>
  CW5  VSS838  POWER  = GND
  CW7  UPI1_TX_DP13  OUT  = UPI_CPU0_CPU1_P1P0_DN<13>
  CW9  VSS850  POWER  = GND
  CW11  PE2_RX_DP1  IN  = P5E_CPU0_PE2_RX_DP<1>
  CW13  VSS836  POWER  = GND
  CW15  PE2_TX_DP1  OUT  = P5E_CPU0_PE2_TX_DP<1>
  CW17  VSS837  POWER  = GND
  CW19  UPI1_AC_COUPLING  IN  = PU_CPU0_UPI1_AC_COUPLING
  CW21  RSVD144  BI  = TP_IBL_SLPS5_CPU0_R_N
  CW23  RSVD145  BI  = NC_CPU0_VIEWPIN_DIE10<3>
  CW25  RSVD146  BI  = NC_CPU0_VIEWPIN_DIE10<1>
  CW27  BCLK3_DN  IN  = CLK_100M_DB2000_CPU0_BCLK3_DN
  CW29  BCLK1_DP  IN  = CLK_100M_DB2000_CPU0_BCLK1_DP
  CW31  XTAL_CLK_DN  IN  = CLK_25M_NSSC_CPU0_DN
  CW33  VSS583  POWER  = GND
  CW35  VCCD_HV21  POWER  = PVCCD_HV_CPU0
  CW37  VCCD_HV22  POWER  = PVCCD_HV_CPU0
  CW39  PMDOWN0  IN  = H_CPU0_PMDOWN_CPU1_R
  CW41  RSVD147  BI  = NC_CPU0_HBM1_VIEWDIG1
  CW43  RSVD148  BI  = TP_CPU0_SPARE6
  CW45  DDR67_DRAM_PWR_OK  IN  = PWRGD_DRAMPWRGD_CPU0_GH_LVC1_R
  CW48  DDR5_ALERT_N  IN  = M_F_CPU0_ALERT_N
